(kicad_pcb
	(version 20241229)
	(generator "pcbnew")
	(generator_version "9.0")
	(general
		(thickness 1.61)
		(legacy_teardrops no)
	)
	(paper "A3")
	(title_block
		(title "SO-DIMM DDR5 Tester")
		(date "2025-11-26")
		(rev "1.3.0")
		(comment 9 "footprints 560-565 of 627")
	)
	(layers
		(0 "F.Cu" signal)
		(4 "In1.Cu" power)
		(6 "In2.Cu" mixed)
		(8 "In3.Cu" power)
		(10 "In4.Cu" mixed)
		(12 "In5.Cu" power)
		(14 "In6.Cu" mixed)
		(16 "In7.Cu" power)
		(18 "In8.Cu" power)
		(20 "In9.Cu" mixed)
		(22 "In10.Cu" power)
		(2 "B.Cu" signal)
		(9 "F.Adhes" user "F.Adhesive")
		(11 "B.Adhes" user "B.Adhesive")
		(13 "F.Paste" user)
		(15 "B.Paste" user)
		(5 "F.SilkS" user "F.Silkscreen")
		(7 "B.SilkS" user "B.Silkscreen")
		(1 "F.Mask" user)
		(3 "B.Mask" user)
		(17 "Dwgs.User" user "User.Drawings")
		(19 "Cmts.User" user "User.Comments")
		(21 "Eco1.User" user "User.Eco1")
		(23 "Eco2.User" user "User.Eco2")
		(25 "Edge.Cuts" user)
		(27 "Margin" user)
		(31 "F.CrtYd" user "F.Courtyard")
		(29 "B.CrtYd" user "B.Courtyard")
		(35 "F.Fab" user)
		(33 "B.Fab" user)
	)
	(footprint "antmicro-footprints:C_0402_1005Metric"
		(layer "B.Cu")
		(at 141.875001 179.3025)
		(descr "Capacitor SMD 0402 (1005 Metric), square (rectangular) end terminal, IPC_7351 nominal, (Body size source: IPC-SM-782 page 76, https://www.pcb-3d.com/wordpress/wp-content/uploads/ipc-sm-782a_amendment_1_and_2.pdf)")
		(tags "capacitor 0402")
		(property "Reference" "C13"
			(at 0 1.17 180)
			(layer "B.SilkS")
			(hide yes)
			(effects
				(font
					(size 0.7 0.7)
					(thickness 0.15)
				)
				(justify left bottom mirror)
			)
		)
		(property "Value" "C_100n_0402"
			(at 0 -1.169 180)
			(layer "B.Fab")
			(effects
				(font
					(size 0.7 0.7)
					(thickness 0.15)
				)
				(justify left bottom mirror)
			)
		)
		(property "Datasheet" "https://www.murata.com/products/productdetail?partno=GRM155R61H104KE14%23"
			(at 0 0 0)
			(layer "F.Fab")
			(hide yes)
			(effects
				(font
					(size 1.27 1.27)
					(thickness 0.15)
				)
			)
		)
		(property "Author" "Antmicro"
			(at 0 0 0)
			(layer "B.Fab")
			(hide yes)
			(effects
				(font
					(size 1 1)
					(thickness 0.15)
				)
				(justify mirror)
			)
		)
		(property "Dielectric" "X5R"
			(at 0 0 0)
			(layer "B.Fab")
			(hide yes)
			(effects
				(font
					(size 1 1)
					(thickness 0.15)
				)
				(justify mirror)
			)
		)
		(property "License" "Apache-2.0"
			(at 0 0 0)
			(layer "B.Fab")
			(hide yes)
			(effects
				(font
					(size 1 1)
					(thickness 0.15)
				)
				(justify mirror)
			)
		)
		(property "MPN" "GRM155R61H104KE14D"
			(at 0 0 0)
			(layer "B.Fab")
			(hide yes)
			(effects
				(font
					(size 1 1)
					(thickness 0.15)
				)
				(justify mirror)
			)
		)
		(property "Manufacturer" "Murata"
			(at 0 0 0)
			(layer "B.Fab")
			(hide yes)
			(effects
				(font
					(size 1 1)
					(thickness 0.15)
				)
				(justify mirror)
			)
		)
		(property "Val" "100n"
			(at 0 0 0)
			(layer "B.Fab")
			(hide yes)
			(effects
				(font
					(size 1 1)
					(thickness 0.15)
				)
				(justify mirror)
			)
		)
		(property "Voltage" "50V"
			(at 0 0 0)
			(layer "B.Fab")
			(hide yes)
			(effects
				(font
					(size 1 1)
					(thickness 0.15)
				)
				(justify mirror)
			)
		)
		(sheetname "/FPGA power/")
		(sheetfile "fpga-power.kicad_sch")
		(attr smd)
		(fp_rect
			(start -0.9656 0.4572)
			(end 0.9652 -0.4828)
			(stroke
				(width 0.05)
				(type solid)
			)
			(fill no)
			(layer "B.CrtYd")
		)
		(fp_line
			(start -0.5 -0.248)
			(end -0.5 0.25)
			(stroke
				(width 0.15)
				(type solid)
			)
			(layer "B.Fab")
		)
		(fp_line
			(start -0.5 0.25)
			(end 0.498 0.25)
			(stroke
				(width 0.15)
				(type solid)
			)
			(layer "B.Fab")
		)
		(fp_line
			(start 0.498 -0.248)
			(end -0.5 -0.248)
			(stroke
				(width 0.15)
				(type solid)
			)
			(layer "B.Fab")
		)
		(fp_line
			(start 0.498 0.25)
			(end 0.498 -0.248)
			(stroke
				(width 0.15)
				(type solid)
			)
			(layer "B.Fab")
		)
		(pad "1" smd roundrect
			(at -0.5 0 270)
			(size 0.6 0.6)
			(layers "B.Cu" "B.Mask" "B.Paste")
			(roundrect_rratio 0.25)
			(net 1 "GND")
			(pintype "passive")
		)
		(pad "2" smd roundrect
			(at 0.498 0)
			(size 0.6 0.6)
			(layers "B.Cu" "B.Mask" "B.Paste")
			(roundrect_rratio 0.25)
			(net 227 "+1V0")
			(pintype "passive")
		)
	)
	(footprint "antmicro-footprints:C_0402_1005Metric"
		(layer "B.Cu")
		(at 137.375501 168.801 90)
		(descr "Capacitor SMD 0402 (1005 Metric), square (rectangular) end terminal, IPC_7351 nominal, (Body size source: IPC-SM-782 page 76, https://www.pcb-3d.com/wordpress/wp-content/uploads/ipc-sm-782a_amendment_1_and_2.pdf)")
		(tags "capacitor 0402")
		(property "Reference" "C49"
			(at 0 1.17 270)
			(layer "B.SilkS")
			(hide yes)
			(effects
				(font
					(size 0.7 0.7)
					(thickness 0.15)
				)
				(justify left bottom mirror)
			)
		)
		(property "Value" "C_100n_0402"
			(at 0 -1.169 270)
			(layer "B.Fab")
			(effects
				(font
					(size 0.7 0.7)
					(thickness 0.15)
				)
				(justify left bottom mirror)
			)
		)
		(property "Datasheet" "https://www.murata.com/products/productdetail?partno=GRM155R61H104KE14%23"
			(at 0 0 90)
			(layer "F.Fab")
			(hide yes)
			(effects
				(font
					(size 1.27 1.27)
					(thickness 0.15)
				)
			)
		)
		(property "Author" "Antmicro"
			(at 306.176501 31.425499 0)
			(layer "B.Fab")
			(hide yes)
			(effects
				(font
					(size 1 1)
					(thickness 0.15)
				)
				(justify mirror)
			)
		)
		(property "Dielectric" "X5R"
			(at 306.176501 31.425499 0)
			(layer "B.Fab")
			(hide yes)
			(effects
				(font
					(size 1 1)
					(thickness 0.15)
				)
				(justify mirror)
			)
		)
		(property "License" "Apache-2.0"
			(at 306.176501 31.425499 0)
			(layer "B.Fab")
			(hide yes)
			(effects
				(font
					(size 1 1)
					(thickness 0.15)
				)
				(justify mirror)
			)
		)
		(property "MPN" "GRM155R61H104KE14D"
			(at 306.176501 31.425499 0)
			(layer "B.Fab")
			(hide yes)
			(effects
				(font
					(size 1 1)
					(thickness 0.15)
				)
				(justify mirror)
			)
		)
		(property "Manufacturer" "Murata"
			(at 306.176501 31.425499 0)
			(layer "B.Fab")
			(hide yes)
			(effects
				(font
					(size 1 1)
					(thickness 0.15)
				)
				(justify mirror)
			)
		)
		(property "Val" "100n"
			(at 306.176501 31.425499 0)
			(layer "B.Fab")
			(hide yes)
			(effects
				(font
					(size 1 1)
					(thickness 0.15)
				)
				(justify mirror)
			)
		)
		(property "Voltage" "50V"
			(at 306.176501 31.425499 0)
			(layer "B.Fab")
			(hide yes)
			(effects
				(font
					(size 1 1)
					(thickness 0.15)
				)
				(justify mirror)
			)
		)
		(sheetname "/FPGA power/")
		(sheetfile "fpga-power.kicad_sch")
		(attr smd)
		(fp_rect
			(start -0.9656 0.4572)
			(end 0.9652 -0.4828)
			(stroke
				(width 0.05)
				(type solid)
			)
			(fill no)
			(layer "B.CrtYd")
		)
		(fp_line
			(start 0.498 -0.248)
			(end -0.5 -0.248)
			(stroke
				(width 0.15)
				(type solid)
			)
			(layer "B.Fab")
		)
		(fp_line
			(start -0.5 -0.248)
			(end -0.5 0.25)
			(stroke
				(width 0.15)
				(type solid)
			)
			(layer "B.Fab")
		)
		(fp_line
			(start 0.498 0.25)
			(end 0.498 -0.248)
			(stroke
				(width 0.15)
				(type solid)
			)
			(layer "B.Fab")
		)
		(fp_line
			(start -0.5 0.25)
			(end 0.498 0.25)
			(stroke
				(width 0.15)
				(type solid)
			)
			(layer "B.Fab")
		)
		(pad "1" smd roundrect
			(at -0.5 0)
			(size 0.6 0.6)
			(layers "B.Cu" "B.Mask" "B.Paste")
			(roundrect_rratio 0.25)
			(net 1 "GND")
			(pintype "passive")
		)
		(pad "2" smd roundrect
			(at 0.498 0 90)
			(size 0.6 0.6)
			(layers "B.Cu" "B.Mask" "B.Paste")
			(roundrect_rratio 0.25)
			(net 206 "+1V1")
			(pintype "passive")
		)
	)
	(footprint "antmicro-footprints:C_0402_1005Metric"
		(layer "B.Cu")
		(at 146.375001 181.8025 90)
		(descr "Capacitor SMD 0402 (1005 Metric), square (rectangular) end terminal, IPC_7351 nominal, (Body size source: IPC-SM-782 page 76, https://www.pcb-3d.com/wordpress/wp-content/uploads/ipc-sm-782a_amendment_1_and_2.pdf)")
		(tags "capacitor 0402")
		(property "Reference" "C100"
			(at 0 1.17 270)
			(layer "B.SilkS")
			(hide yes)
			(effects
				(font
					(size 0.7 0.7)
					(thickness 0.15)
				)
				(justify left bottom mirror)
			)
		)
		(property "Value" "C_100n_0402"
			(at 0 -1.169 270)
			(layer "B.Fab")
			(effects
				(font
					(size 0.7 0.7)
					(thickness 0.15)
				)
				(justify left bottom mirror)
			)
		)
		(property "Datasheet" "https://www.murata.com/products/productdetail?partno=GRM155R61H104KE14%23"
			(at 0 0 90)
			(layer "F.Fab")
			(hide yes)
			(effects
				(font
					(size 1.27 1.27)
					(thickness 0.15)
				)
			)
		)
		(property "Author" "Antmicro"
			(at 328.177501 35.427499 0)
			(layer "B.Fab")
			(hide yes)
			(effects
				(font
					(size 1 1)
					(thickness 0.15)
				)
				(justify mirror)
			)
		)
		(property "Dielectric" "X5R"
			(at 328.177501 35.427499 0)
			(layer "B.Fab")
			(hide yes)
			(effects
				(font
					(size 1 1)
					(thickness 0.15)
				)
				(justify mirror)
			)
		)
		(property "License" "Apache-2.0"
			(at 328.177501 35.427499 0)
			(layer "B.Fab")
			(hide yes)
			(effects
				(font
					(size 1 1)
					(thickness 0.15)
				)
				(justify mirror)
			)
		)
		(property "MPN" "GRM155R61H104KE14D"
			(at 328.177501 35.427499 0)
			(layer "B.Fab")
			(hide yes)
			(effects
				(font
					(size 1 1)
					(thickness 0.15)
				)
				(justify mirror)
			)
		)
		(property "Manufacturer" "Murata"
			(at 328.177501 35.427499 0)
			(layer "B.Fab")
			(hide yes)
			(effects
				(font
					(size 1 1)
					(thickness 0.15)
				)
				(justify mirror)
			)
		)
		(property "Val" "100n"
			(at 328.177501 35.427499 0)
			(layer "B.Fab")
			(hide yes)
			(effects
				(font
					(size 1 1)
					(thickness 0.15)
				)
				(justify mirror)
			)
		)
		(property "Voltage" "50V"
			(at 328.177501 35.427499 0)
			(layer "B.Fab")
			(hide yes)
			(effects
				(font
					(size 1 1)
					(thickness 0.15)
				)
				(justify mirror)
			)
		)
		(sheetname "/FPGA power/")
		(sheetfile "fpga-power.kicad_sch")
		(attr smd)
		(fp_rect
			(start -0.9656 0.4572)
			(end 0.9652 -0.4828)
			(stroke
				(width 0.05)
				(type solid)
			)
			(fill no)
			(layer "B.CrtYd")
		)
		(fp_line
			(start 0.498 -0.248)
			(end -0.5 -0.248)
			(stroke
				(width 0.15)
				(type solid)
			)
			(layer "B.Fab")
		)
		(fp_line
			(start -0.5 -0.248)
			(end -0.5 0.25)
			(stroke
				(width 0.15)
				(type solid)
			)
			(layer "B.Fab")
		)
		(fp_line
			(start 0.498 0.25)
			(end 0.498 -0.248)
			(stroke
				(width 0.15)
				(type solid)
			)
			(layer "B.Fab")
		)
		(fp_line
			(start -0.5 0.25)
			(end 0.498 0.25)
			(stroke
				(width 0.15)
				(type solid)
			)
			(layer "B.Fab")
		)
		(pad "1" smd roundrect
			(at -0.5 0)
			(size 0.6 0.6)
			(layers "B.Cu" "B.Mask" "B.Paste")
			(roundrect_rratio 0.25)
			(net 1 "GND")
			(pintype "passive")
		)
		(pad "2" smd roundrect
			(at 0.498 0 90)
			(size 0.6 0.6)
			(layers "B.Cu" "B.Mask" "B.Paste")
			(roundrect_rratio 0.25)
			(net 187 "+1V0_MGTAVCC")
			(pintype "passive")
		)
	)
	(footprint "antmicro-footprints:R_0402_1005Metric"
		(layer "B.Cu")
		(at 180.8 191 180)
		(descr "Resistor SMD 0402")
		(tags "resistor SMD 0402")
		(property "Reference" "R177"
			(at 1.25 -0.4 0)
			(layer "B.SilkS")
			(effects
				(font
					(size 0.7 0.7)
					(thickness 0.15)
				)
				(justify left bottom mirror)
			)
		)
		(property "Value" "R_0R_0402"
			(at -1.011843 -1.772047 0)
			(layer "B.Fab")
			(effects
				(font
					(size 0.7 0.7)
					(thickness 0.15)
				)
				(justify left bottom mirror)
			)
		)
		(property "Datasheet" "https://industrial.panasonic.com/cdbs/www-data/pdf/RDA0000/AOA0000C301.pdf"
			(at 0 0 180)
			(layer "F.Fab")
			(hide yes)
			(effects
				(font
					(size 1.27 1.27)
					(thickness 0.15)
				)
			)
		)
		(property "Author" "Antmicro"
			(at 361.6 382 0)
			(layer "B.Fab")
			(hide yes)
			(effects
				(font
					(size 1 1)
					(thickness 0.15)
				)
				(justify mirror)
			)
		)
		(property "Current" "1A"
			(at 361.6 382 0)
			(layer "B.Fab")
			(hide yes)
			(effects
				(font
					(size 1 1)
					(thickness 0.15)
				)
				(justify mirror)
			)
		)
		(property "License" "Apache-2.0"
			(at 361.6 382 0)
			(layer "B.Fab")
			(hide yes)
			(effects
				(font
					(size 1 1)
					(thickness 0.15)
				)
				(justify mirror)
			)
		)
		(property "MPN" "ERJ2GE0R00X"
			(at 361.6 382 0)
			(layer "B.Fab")
			(hide yes)
			(effects
				(font
					(size 1 1)
					(thickness 0.15)
				)
				(justify mirror)
			)
		)
		(property "Manufacturer" "Panasonic"
			(at 361.6 382 0)
			(layer "B.Fab")
			(hide yes)
			(effects
				(font
					(size 1 1)
					(thickness 0.15)
				)
				(justify mirror)
			)
		)
		(property "Tolerance" ""
			(at 361.6 382 0)
			(layer "B.Fab")
			(hide yes)
			(effects
				(font
					(size 1 1)
					(thickness 0.15)
				)
				(justify mirror)
			)
		)
		(property "Val" "0R"
			(at 361.6 382 0)
			(layer "B.Fab")
			(hide yes)
			(effects
				(font
					(size 1 1)
					(thickness 0.15)
				)
				(justify mirror)
			)
		)
		(sheetname "/I^{2}C/")
		(sheetfile "i2c.kicad_sch")
		(attr exclude_from_pos_files exclude_from_bom dnp)
		(fp_rect
			(start -0.93 0.47)
			(end 0.93 -0.47)
			(stroke
				(width 0.05)
				(type solid)
			)
			(fill no)
			(layer "B.CrtYd")
		)
		(fp_rect
			(start -0.5 0.25)
			(end 0.5 -0.25)
			(stroke
				(width 0.15)
				(type solid)
			)
			(fill no)
			(layer "B.Fab")
		)
		(pad "1" smd roundrect
			(at -0.485 0 180)
			(size 0.59 0.64)
			(layers "B.Cu" "B.Mask" "B.Paste")
			(roundrect_rratio 0.25)
			(net 691 "/I^{2}C/PWR.SCL")
			(pintype "passive")
		)
		(pad "2" smd roundrect
			(at 0.485 0 180)
			(size 0.59 0.64)
			(layers "B.Cu" "B.Mask" "B.Paste")
			(roundrect_rratio 0.25)
			(net 682 "/FPGA bank 14/FPGA_DDR.SCL")
			(pintype "passive")
		)
	)
	(footprint "antmicro-footprints:R_0402_1005Metric"
		(layer "B.Cu")
		(at 107.4 142.4 90)
		(descr "Resistor SMD 0402")
		(tags "resistor SMD 0402")
		(property "Reference" "R33"
			(at 3.044968 0.254606 270)
			(layer "B.SilkS")
			(effects
				(font
					(size 0.7 0.7)
					(thickness 0.15)
				)
				(justify left bottom mirror)
			)
		)
		(property "Value" "R_0R_0402"
			(at -1.011843 -1.772047 270)
			(layer "B.Fab")
			(effects
				(font
					(size 0.7 0.7)
					(thickness 0.15)
				)
				(justify left bottom mirror)
			)
		)
		(property "Datasheet" "https://industrial.panasonic.com/cdbs/www-data/pdf/RDA0000/AOA0000C301.pdf"
			(at 0 0 90)
			(layer "F.Fab")
			(hide yes)
			(effects
				(font
					(size 1.27 1.27)
					(thickness 0.15)
				)
			)
		)
		(property "Author" "Antmicro"
			(at 249.8 35 0)
			(layer "B.Fab")
			(hide yes)
			(effects
				(font
					(size 1 1)
					(thickness 0.15)
				)
				(justify mirror)
			)
		)
		(property "Current" "1A"
			(at 249.8 35 0)
			(layer "B.Fab")
			(hide yes)
			(effects
				(font
					(size 1 1)
					(thickness 0.15)
				)
				(justify mirror)
			)
		)
		(property "License" "Apache-2.0"
			(at 249.8 35 0)
			(layer "B.Fab")
			(hide yes)
			(effects
				(font
					(size 1 1)
					(thickness 0.15)
				)
				(justify mirror)
			)
		)
		(property "MPN" "ERJ2GE0R00X"
			(at 249.8 35 0)
			(layer "B.Fab")
			(hide yes)
			(effects
				(font
					(size 1 1)
					(thickness 0.15)
				)
				(justify mirror)
			)
		)
		(property "Manufacturer" "Panasonic"
			(at 249.8 35 0)
			(layer "B.Fab")
			(hide yes)
			(effects
				(font
					(size 1 1)
					(thickness 0.15)
				)
				(justify mirror)
			)
		)
		(property "Tolerance" ""
			(at 249.8 35 0)
			(layer "B.Fab")
			(hide yes)
			(effects
				(font
					(size 1 1)
					(thickness 0.15)
				)
				(justify mirror)
			)
		)
		(property "Val" "0R"
			(at 249.8 35 0)
			(layer "B.Fab")
			(hide yes)
			(effects
				(font
					(size 1 1)
					(thickness 0.15)
				)
				(justify mirror)
			)
		)
		(sheetname "/DDR5 SODIMM/")
		(sheetfile "ddr5-sodimm.kicad_sch")
		(attr exclude_from_pos_files exclude_from_bom dnp)
		(fp_rect
			(start -0.93 0.47)
			(end 0.93 -0.47)
			(stroke
				(width 0.05)
				(type solid)
			)
			(fill no)
			(layer "B.CrtYd")
		)
		(fp_rect
			(start -0.5 0.25)
			(end 0.5 -0.25)
			(stroke
				(width 0.15)
				(type solid)
			)
			(fill no)
			(layer "B.Fab")
		)
		(pad "1" smd roundrect
			(at -0.485 0 90)
			(size 0.59 0.64)
			(layers "B.Cu" "B.Mask" "B.Paste")
			(roundrect_rratio 0.25)
			(net 137 "/DDR5 SODIMM/RFU1")
			(pintype "passive")
		)
		(pad "2" smd roundrect
			(at 0.485 0 90)
			(size 0.59 0.64)
			(layers "B.Cu" "B.Mask" "B.Paste")
			(roundrect_rratio 0.25)
			(net 273 "RFU_1")
			(pintype "passive")
		)
	)
	(footprint "antmicro-footprints:TP_SMD_1mm"
		(layer "B.Cu")
		(at 203.1 154.3 90)
		(property "Reference" "TP37"
			(at -3.4 -0.3 90)
			(layer "B.SilkS")
			(effects
				(font
					(size 0.7 0.7)
					(thickness 0.15)
				)
				(justify right top mirror)
			)
		)
		(property "Value" "TP_1mm_SMD"
			(at 0 -1.4 90)
			(layer "B.Fab")
			(effects
				(font
					(size 0.7 0.7)
					(thickness 0.15)
				)
				(justify right top mirror)
			)
		)
		(property "MPN" ""
			(at 0 0 270)
			(unlocked yes)
			(layer "B.Fab")
			(hide yes)
			(effects
				(font
					(size 1 1)
					(thickness 0.15)
				)
				(justify mirror)
			)
		)
		(property "Manufacturer" ""
			(at 0 0 270)
			(unlocked yes)
			(layer "B.Fab")
			(hide yes)
			(effects
				(font
					(size 1 1)
					(thickness 0.15)
				)
				(justify mirror)
			)
		)
		(property "Author" "Antmicro"
			(at 0 0 270)
			(unlocked yes)
			(layer "B.Fab")
			(hide yes)
			(effects
				(font
					(size 1 1)
					(thickness 0.15)
				)
				(justify mirror)
			)
		)
		(property "License" "Apache-2.0"
			(at 0 0 270)
			(unlocked yes)
			(layer "B.Fab")
			(hide yes)
			(effects
				(font
					(size 1 1)
					(thickness 0.15)
				)
				(justify mirror)
			)
		)
		(sheetname "/I^{2}C/")
		(sheetfile "i2c.kicad_sch")
		(attr exclude_from_pos_files)
		(fp_circle
			(center 0 0)
			(end 0.6 0)
			(stroke
				(width 0.05)
				(type default)
			)
			(fill no)
			(layer "B.CrtYd")
		)
		(fp_text user "Author: Antmicro"
			(at -0.5 -4 90)
			(layer "B.Fab")
			(effects
				(font
					(size 0.7 0.7)
					(thickness 0.15)
				)
				(justify right top mirror)
			)
		)
		(fp_text user "License: Apache-2.0"
			(at -0.5 -5.2 90)
			(layer "B.Fab")
			(effects
				(font
					(size 0.7 0.7)
					(thickness 0.15)
				)
				(justify right top mirror)
			)
		)
		(fp_text user "${REFERENCE}"
			(at -0.5 -2.8 90)
			(layer "B.Fab")
			(effects
				(font
					(size 0.7 0.7)
					(thickness 0.15)
				)
				(justify right top mirror)
			)
		)
		(pad "1" smd circle
			(at 0 0 90)
			(size 1 1)
			(layers "B.Cu" "B.Mask")
			(net 691 "/I^{2}C/PWR.SCL")
			(pinfunction "1")
			(pintype "passive")
		)
	)
)
